(kicad_pcb
	(version 20260206)
	(generator "pcbnew")
	(generator_version "10.0")
	(general
		(thickness 1.6)
		(legacy_teardrops no)
	)
	(paper "A4")
	(title_block
		(title "panther-plus-userver — 13130-1b_20150205.brd")
		(comment 1 "Honey Badger (Wiwynn) / footprint 624 of 1509 (DIMM4), pads 58-64 of 210")
	)
	(layers
		(0 "F.Cu" signal "TOP")
		(4 "In1.Cu" signal "L2")
		(6 "In2.Cu" signal "L3")
		(8 "In3.Cu" signal "L4")
		(10 "In4.Cu" signal "L5")
		(12 "In5.Cu" signal "L6")
		(14 "In6.Cu" signal "L7")
		(16 "In7.Cu" signal "L8")
		(18 "In8.Cu" signal "L9")
		(20 "In9.Cu" signal "L10")
		(22 "In10.Cu" signal "L11")
		(2 "B.Cu" signal "BOTTOM")
		(9 "F.Adhes" user "F.Adhesive")
		(11 "B.Adhes" user "B.Adhesive")
		(13 "F.Paste" user "Package Geometry/Pastemask Top")
		(15 "B.Paste" user "Package Geometry/Pastemask Bottom")
		(5 "F.SilkS" user "Ref Des/Silkscreen Top")
		(7 "B.SilkS" user "Ref Des/Silkscreen Bottom")
		(1 "F.Mask" user "Board Geometry/Soldermask Top")
		(3 "B.Mask" user "Board Geometry/Soldermask Bottom")
		(17 "Dwgs.User" user "User.Drawings")
		(19 "Cmts.User" user "User.Comments")
		(21 "Eco1.User" user "User.Eco1")
		(23 "Eco2.User" user "User.Eco2")
		(25 "Edge.Cuts" user "Board Geometry/Outline")
		(27 "Margin" user)
		(31 "F.CrtYd" user "Package Geometry/Place Bound Top")
		(29 "B.CrtYd" user "Package Geometry/Place Bound Bottom")
		(35 "F.Fab" user "Ref Des/Assembly Top")
		(33 "B.Fab" user "Ref Des/Assembly Bottom")
	)
	(footprint ""
		(layer "F.Cu")
		(at 159.999934 -5.790692)
		(property "Reference" "DIMM4"
			(at 0 0 0)
			(layer "F.SilkS")
			(hide yes)
			(effects
				(font
					(size 1.27 1.27)
				)
			)
		)
		(property "Value" "DDR3-204P-174-COLAY-1-GP"
			(at -40.682164 -17.468088 0)
			(unlocked yes)
			(layer "F.Fab")
			(hide yes)
			(effects
				(font
					(size 1.016 1.016)
					(thickness 0.1524)
				)
			)
		)
		(property "Device Type" "AS0A626-H8SN-7H-COLAY-1"
			(at -40.682164 -18.992088 0)
			(unlocked yes)
			(layer "F.Fab")
			(hide yes)
			(effects
				(font
					(size 1.016 1.016)
					(thickness 0.1524)
				)
			)
		)
		(duplicate_pad_numbers_are_jumpers no)
		(pad "56" smd custom
			(at -15.150084 -4.106672)
			(size 0.1143 0.1143)
			(layers "F.Cu" "F.Mask" "F.Paste")
			(net "M_B_DQ25")
			(options
				(clearance outline)
				(anchor circle)
			)
			(primitives
				(gr_poly
					(pts
						(xy 0 0.9017) (xy -0.03175 0.89916) (xy -0.0635 0.889) (xy -0.09144 0.87376) (xy -0.11684 0.85344)
						(xy -0.13716 0.82804) (xy -0.1524 0.8001) (xy -0.16256 0.76835) (xy -0.1651 0.7366) (xy -0.1651 0.19685)
						(xy -0.17272 0.18923) (xy -0.17907 0.18034) (xy -0.18669 0.17145) (xy -0.19177 0.16256) (xy -0.19812 0.15367)
						(xy -0.20828 0.13335) (xy -0.21971 0.10287) (xy -0.22225 0.09271) (xy -0.22479 0.08128) (xy -0.22606 0.07112)
						(xy -0.2286 0.05969) (xy -0.2286 0.01651) (xy -0.22606 0.00508) (xy -0.22479 -0.00508) (xy -0.22225 -0.01651)
						(xy -0.21971 -0.02667) (xy -0.20828 -0.05715) (xy -0.19812 -0.07747) (xy -0.19177 -0.08636) (xy -0.18669 -0.09525)
						(xy -0.17907 -0.10414) (xy -0.17272 -0.11303) (xy -0.1651 -0.12065) (xy -0.1651 -0.7366) (xy -0.16256 -0.76835)
						(xy -0.1524 -0.8001) (xy -0.13716 -0.82804) (xy -0.11684 -0.85344) (xy -0.09144 -0.87376) (xy -0.0635 -0.889)
						(xy -0.03175 -0.89916) (xy 0 -0.9017) (xy 0.03175 -0.89916) (xy 0.0635 -0.889) (xy 0.09144 -0.87376)
						(xy 0.11684 -0.85344) (xy 0.13716 -0.82804) (xy 0.1524 -0.8001) (xy 0.16256 -0.76835) (xy 0.1651 -0.7366)
						(xy 0.1651 -0.11938) (xy 0.17272 -0.11176) (xy 0.19812 -0.0762) (xy 0.2032 -0.06604) (xy 0.20701 -0.05715)
						(xy 0.21209 -0.04699) (xy 0.2159 -0.03683) (xy 0.21844 -0.02667) (xy 0.22225 -0.01524) (xy 0.22352 -0.00508)
						(xy 0.22606 0.00508) (xy 0.22733 0.01651) (xy 0.22733 0.02667) (xy 0.2286 0.0381) (xy 0.22733 0.04953)
						(xy 0.22733 0.05969) (xy 0.22606 0.07112) (xy 0.22352 0.08128) (xy 0.22225 0.09144) (xy 0.21844 0.10287)
						(xy 0.2159 0.11303) (xy 0.21209 0.12319) (xy 0.20701 0.13335) (xy 0.2032 0.14224) (xy 0.19812 0.1524)
						(xy 0.17272 0.18796) (xy 0.1651 0.19558) (xy 0.1651 0.7366) (xy 0.16256 0.76835) (xy 0.1524 0.8001)
						(xy 0.13716 0.82804) (xy 0.11684 0.85344) (xy 0.09144 0.87376) (xy 0.0635 0.889) (xy 0.03175 0.89916)
					)
					(width 0)
					(fill yes)
				)
			)
		)
		(pad "57" smd custom
			(at -14.85011 4.106672)
			(size 0.1143 0.1143)
			(layers "F.Cu" "F.Mask" "F.Paste")
			(net "M_B_DQ29")
			(options
				(clearance outline)
				(anchor circle)
			)
			(primitives
				(gr_poly
					(pts
						(xy 0 0.9017) (xy -0.03175 0.89916) (xy -0.0635 0.889) (xy -0.09144 0.87376) (xy -0.11684 0.85344)
						(xy -0.13716 0.82804) (xy -0.1524 0.8001) (xy -0.16256 0.76835) (xy -0.1651 0.7366) (xy -0.1651 -0.13462)
						(xy -0.17272 -0.14224) (xy -0.19812 -0.1778) (xy -0.2032 -0.18796) (xy -0.20701 -0.19685) (xy -0.21209 -0.20701)
						(xy -0.2159 -0.21717) (xy -0.21844 -0.22733) (xy -0.22225 -0.23876) (xy -0.22352 -0.24892) (xy -0.22606 -0.25908)
						(xy -0.22733 -0.27051) (xy -0.22733 -0.28067) (xy -0.2286 -0.2921) (xy -0.22733 -0.30353) (xy -0.22733 -0.31369)
						(xy -0.22606 -0.32512) (xy -0.22352 -0.33528) (xy -0.22225 -0.34544) (xy -0.21844 -0.35687) (xy -0.2159 -0.36703)
						(xy -0.21209 -0.37719) (xy -0.20701 -0.38735) (xy -0.2032 -0.39624) (xy -0.19812 -0.4064) (xy -0.17272 -0.44196)
						(xy -0.1651 -0.44958) (xy -0.1651 -0.7366) (xy -0.16256 -0.76835) (xy -0.1524 -0.8001) (xy -0.13716 -0.82804)
						(xy -0.11684 -0.85344) (xy -0.09144 -0.87376) (xy -0.0635 -0.889) (xy -0.03175 -0.89916) (xy 0 -0.9017)
						(xy 0.03175 -0.89916) (xy 0.0635 -0.889) (xy 0.09144 -0.87376) (xy 0.11684 -0.85344) (xy 0.13716 -0.82804)
						(xy 0.1524 -0.8001) (xy 0.16256 -0.76835) (xy 0.1651 -0.7366) (xy 0.1651 -0.44958) (xy 0.17272 -0.44196)
						(xy 0.19812 -0.4064) (xy 0.2032 -0.39624) (xy 0.20701 -0.38735) (xy 0.21209 -0.37719) (xy 0.2159 -0.36703)
						(xy 0.21844 -0.35687) (xy 0.22225 -0.34544) (xy 0.22352 -0.33528) (xy 0.22606 -0.32512) (xy 0.22733 -0.31369)
						(xy 0.22733 -0.30353) (xy 0.2286 -0.2921) (xy 0.22733 -0.28067) (xy 0.22733 -0.27051) (xy 0.22606 -0.25908)
						(xy 0.22352 -0.24892) (xy 0.22225 -0.23876) (xy 0.21844 -0.22733) (xy 0.2159 -0.21717) (xy 0.21209 -0.20701)
						(xy 0.20701 -0.19685) (xy 0.2032 -0.18796) (xy 0.19812 -0.1778) (xy 0.17272 -0.14224) (xy 0.1651 -0.13462)
						(xy 0.1651 0.7366) (xy 0.16256 0.76835) (xy 0.1524 0.8001) (xy 0.13716 0.82804) (xy 0.11684 0.85344)
						(xy 0.09144 0.87376) (xy 0.0635 0.889) (xy 0.03175 0.89916)
					)
					(width 0)
					(fill yes)
				)
			)
		)
		(pad "58" smd custom
			(at -14.549882 -4.106672)
			(size 0.1143 0.1143)
			(layers "F.Cu" "F.Mask" "F.Paste")
			(net "GND")
			(options
				(clearance outline)
				(anchor circle)
			)
			(primitives
				(gr_poly
					(pts
						(xy 0 0.9017) (xy -0.03175 0.89916) (xy -0.0635 0.889) (xy -0.09144 0.87376) (xy -0.11684 0.85344)
						(xy -0.13716 0.82804) (xy -0.1524 0.8001) (xy -0.16256 0.76835) (xy -0.1651 0.7366) (xy -0.1651 0.44958)
						(xy -0.17272 0.44196) (xy -0.19812 0.4064) (xy -0.2032 0.39624) (xy -0.20701 0.38735) (xy -0.21209 0.37719)
						(xy -0.2159 0.36703) (xy -0.21844 0.35687) (xy -0.22225 0.34544) (xy -0.22352 0.33528) (xy -0.22606 0.32512)
						(xy -0.22733 0.31369) (xy -0.22733 0.30353) (xy -0.2286 0.2921) (xy -0.22733 0.28067) (xy -0.22733 0.27051)
						(xy -0.22606 0.25908) (xy -0.22352 0.24892) (xy -0.22225 0.23876) (xy -0.21844 0.22733) (xy -0.2159 0.21717)
						(xy -0.21209 0.20701) (xy -0.20701 0.19685) (xy -0.2032 0.18796) (xy -0.19812 0.1778) (xy -0.17272 0.14224)
						(xy -0.1651 0.13462) (xy -0.1651 -0.7366) (xy -0.16256 -0.76835) (xy -0.1524 -0.8001) (xy -0.13716 -0.82804)
						(xy -0.11684 -0.85344) (xy -0.09144 -0.87376) (xy -0.0635 -0.889) (xy -0.03175 -0.89916) (xy 0 -0.9017)
						(xy 0.03175 -0.89916) (xy 0.0635 -0.889) (xy 0.09144 -0.87376) (xy 0.11684 -0.85344) (xy 0.13716 -0.82804)
						(xy 0.1524 -0.8001) (xy 0.16256 -0.76835) (xy 0.1651 -0.7366) (xy 0.1651 0.13462) (xy 0.17272 0.14224)
						(xy 0.19812 0.1778) (xy 0.2032 0.18796) (xy 0.20701 0.19685) (xy 0.21209 0.20701) (xy 0.2159 0.21717)
						(xy 0.21844 0.22733) (xy 0.22225 0.23876) (xy 0.22352 0.24892) (xy 0.22606 0.25908) (xy 0.22733 0.27051)
						(xy 0.22733 0.28067) (xy 0.2286 0.2921) (xy 0.22733 0.30353) (xy 0.22733 0.31369) (xy 0.22606 0.32512)
						(xy 0.22352 0.33528) (xy 0.22225 0.34544) (xy 0.21844 0.35687) (xy 0.2159 0.36703) (xy 0.21209 0.37719)
						(xy 0.20701 0.38735) (xy 0.2032 0.39624) (xy 0.19812 0.4064) (xy 0.17272 0.44196) (xy 0.1651 0.44958)
						(xy 0.1651 0.7366) (xy 0.16256 0.76835) (xy 0.1524 0.8001) (xy 0.13716 0.82804) (xy 0.11684 0.85344)
						(xy 0.09144 0.87376) (xy 0.0635 0.889) (xy 0.03175 0.89916)
					)
					(width 0)
					(fill yes)
				)
			)
		)
		(pad "59" smd custom
			(at -14.249908 4.106672)
			(size 0.1143 0.1143)
			(layers "F.Cu" "F.Mask" "F.Paste")
			(net "GND")
			(options
				(clearance outline)
				(anchor circle)
			)
			(primitives
				(gr_poly
					(pts
						(xy 0 0.9017) (xy -0.03175 0.89916) (xy -0.0635 0.889) (xy -0.09144 0.87376) (xy -0.11684 0.85344)
						(xy -0.13716 0.82804) (xy -0.1524 0.8001) (xy -0.16256 0.76835) (xy -0.1651 0.7366) (xy -0.1651 0.11938)
						(xy -0.17272 0.11176) (xy -0.19812 0.0762) (xy -0.2032 0.06604) (xy -0.20701 0.05715) (xy -0.21209 0.04699)
						(xy -0.2159 0.03683) (xy -0.21844 0.02667) (xy -0.22225 0.01524) (xy -0.22352 0.00508) (xy -0.22606 -0.00508)
						(xy -0.22733 -0.01651) (xy -0.22733 -0.02667) (xy -0.2286 -0.0381) (xy -0.22733 -0.04953) (xy -0.22733 -0.05969)
						(xy -0.22606 -0.07112) (xy -0.22352 -0.08128) (xy -0.22225 -0.09144) (xy -0.21844 -0.10287) (xy -0.2159 -0.11303)
						(xy -0.21209 -0.12319) (xy -0.20701 -0.13335) (xy -0.2032 -0.14224) (xy -0.19812 -0.1524) (xy -0.17272 -0.18796)
						(xy -0.1651 -0.19558) (xy -0.1651 -0.7366) (xy -0.16256 -0.76835) (xy -0.1524 -0.8001) (xy -0.13716 -0.82804)
						(xy -0.11684 -0.85344) (xy -0.09144 -0.87376) (xy -0.0635 -0.889) (xy -0.03175 -0.89916) (xy 0 -0.9017)
						(xy 0.03175 -0.89916) (xy 0.0635 -0.889) (xy 0.09144 -0.87376) (xy 0.11684 -0.85344) (xy 0.13716 -0.82804)
						(xy 0.1524 -0.8001) (xy 0.16256 -0.76835) (xy 0.1651 -0.7366) (xy 0.1651 -0.19685) (xy 0.17272 -0.18923)
						(xy 0.17907 -0.18034) (xy 0.18669 -0.17145) (xy 0.19177 -0.16256) (xy 0.19812 -0.15367) (xy 0.20828 -0.13335)
						(xy 0.21971 -0.10287) (xy 0.22225 -0.09271) (xy 0.22479 -0.08128) (xy 0.22606 -0.07112) (xy 0.2286 -0.05969)
						(xy 0.2286 -0.01651) (xy 0.22606 -0.00508) (xy 0.22479 0.00508) (xy 0.22225 0.01651) (xy 0.21971 0.02667)
						(xy 0.20828 0.05715) (xy 0.19812 0.07747) (xy 0.19177 0.08636) (xy 0.18669 0.09525) (xy 0.17907 0.10414)
						(xy 0.17272 0.11303) (xy 0.1651 0.12065) (xy 0.1651 0.7366) (xy 0.16256 0.76835) (xy 0.1524 0.8001)
						(xy 0.13716 0.82804) (xy 0.11684 0.85344) (xy 0.09144 0.87376) (xy 0.0635 0.889) (xy 0.03175 0.89916)
					)
					(width 0)
					(fill yes)
				)
			)
		)
		(pad "60" smd custom
			(at -13.949934 -4.106672)
			(size 0.1143 0.1143)
			(layers "F.Cu" "F.Mask" "F.Paste")
			(net "M_B_DQS_DN3")
			(options
				(clearance outline)
				(anchor circle)
			)
			(primitives
				(gr_poly
					(pts
						(xy 0 0.9017) (xy -0.03175 0.89916) (xy -0.0635 0.889) (xy -0.09144 0.87376) (xy -0.11684 0.85344)
						(xy -0.13716 0.82804) (xy -0.1524 0.8001) (xy -0.16256 0.76835) (xy -0.1651 0.7366) (xy -0.1651 0.19685)
						(xy -0.17272 0.18923) (xy -0.17907 0.18034) (xy -0.18669 0.17145) (xy -0.19177 0.16256) (xy -0.19812 0.15367)
						(xy -0.20828 0.13335) (xy -0.21971 0.10287) (xy -0.22225 0.09271) (xy -0.22479 0.08128) (xy -0.22606 0.07112)
						(xy -0.2286 0.05969) (xy -0.2286 0.01651) (xy -0.22606 0.00508) (xy -0.22479 -0.00508) (xy -0.22225 -0.01651)
						(xy -0.21971 -0.02667) (xy -0.20828 -0.05715) (xy -0.19812 -0.07747) (xy -0.19177 -0.08636) (xy -0.18669 -0.09525)
						(xy -0.17907 -0.10414) (xy -0.17272 -0.11303) (xy -0.1651 -0.12065) (xy -0.1651 -0.7366) (xy -0.16256 -0.76835)
						(xy -0.1524 -0.8001) (xy -0.13716 -0.82804) (xy -0.11684 -0.85344) (xy -0.09144 -0.87376) (xy -0.0635 -0.889)
						(xy -0.03175 -0.89916) (xy 0 -0.9017) (xy 0.03175 -0.89916) (xy 0.0635 -0.889) (xy 0.09144 -0.87376)
						(xy 0.11684 -0.85344) (xy 0.13716 -0.82804) (xy 0.1524 -0.8001) (xy 0.16256 -0.76835) (xy 0.1651 -0.7366)
						(xy 0.1651 -0.11938) (xy 0.17272 -0.11176) (xy 0.19812 -0.0762) (xy 0.2032 -0.06604) (xy 0.20701 -0.05715)
						(xy 0.21209 -0.04699) (xy 0.2159 -0.03683) (xy 0.21844 -0.02667) (xy 0.22225 -0.01524) (xy 0.22352 -0.00508)
						(xy 0.22606 0.00508) (xy 0.22733 0.01651) (xy 0.22733 0.02667) (xy 0.2286 0.0381) (xy 0.22733 0.04953)
						(xy 0.22733 0.05969) (xy 0.22606 0.07112) (xy 0.22352 0.08128) (xy 0.22225 0.09144) (xy 0.21844 0.10287)
						(xy 0.2159 0.11303) (xy 0.21209 0.12319) (xy 0.20701 0.13335) (xy 0.2032 0.14224) (xy 0.19812 0.1524)
						(xy 0.17272 0.18796) (xy 0.1651 0.19558) (xy 0.1651 0.7366) (xy 0.16256 0.76835) (xy 0.1524 0.8001)
						(xy 0.13716 0.82804) (xy 0.11684 0.85344) (xy 0.09144 0.87376) (xy 0.0635 0.889) (xy 0.03175 0.89916)
					)
					(width 0)
					(fill yes)
				)
			)
		)
		(pad "61" smd custom
			(at -13.64996 4.106672)
			(size 0.1143 0.1143)
			(layers "F.Cu" "F.Mask" "F.Paste")
			(net "GND")
			(options
				(clearance outline)
				(anchor circle)
			)
			(primitives
				(gr_poly
					(pts
						(xy 0 0.9017) (xy -0.03175 0.89916) (xy -0.0635 0.889) (xy -0.09144 0.87376) (xy -0.11684 0.85344)
						(xy -0.13716 0.82804) (xy -0.1524 0.8001) (xy -0.16256 0.76835) (xy -0.1651 0.7366) (xy -0.1651 -0.13462)
						(xy -0.17272 -0.14224) (xy -0.19812 -0.1778) (xy -0.2032 -0.18796) (xy -0.20701 -0.19685) (xy -0.21209 -0.20701)
						(xy -0.2159 -0.21717) (xy -0.21844 -0.22733) (xy -0.22225 -0.23876) (xy -0.22352 -0.24892) (xy -0.22606 -0.25908)
						(xy -0.22733 -0.27051) (xy -0.22733 -0.28067) (xy -0.2286 -0.2921) (xy -0.22733 -0.30353) (xy -0.22733 -0.31369)
						(xy -0.22606 -0.32512) (xy -0.22352 -0.33528) (xy -0.22225 -0.34544) (xy -0.21844 -0.35687) (xy -0.2159 -0.36703)
						(xy -0.21209 -0.37719) (xy -0.20701 -0.38735) (xy -0.2032 -0.39624) (xy -0.19812 -0.4064) (xy -0.17272 -0.44196)
						(xy -0.1651 -0.44958) (xy -0.1651 -0.7366) (xy -0.16256 -0.76835) (xy -0.1524 -0.8001) (xy -0.13716 -0.82804)
						(xy -0.11684 -0.85344) (xy -0.09144 -0.87376) (xy -0.0635 -0.889) (xy -0.03175 -0.89916) (xy 0 -0.9017)
						(xy 0.03175 -0.89916) (xy 0.0635 -0.889) (xy 0.09144 -0.87376) (xy 0.11684 -0.85344) (xy 0.13716 -0.82804)
						(xy 0.1524 -0.8001) (xy 0.16256 -0.76835) (xy 0.1651 -0.7366) (xy 0.1651 -0.44958) (xy 0.17272 -0.44196)
						(xy 0.19812 -0.4064) (xy 0.2032 -0.39624) (xy 0.20701 -0.38735) (xy 0.21209 -0.37719) (xy 0.2159 -0.36703)
						(xy 0.21844 -0.35687) (xy 0.22225 -0.34544) (xy 0.22352 -0.33528) (xy 0.22606 -0.32512) (xy 0.22733 -0.31369)
						(xy 0.22733 -0.30353) (xy 0.2286 -0.2921) (xy 0.22733 -0.28067) (xy 0.22733 -0.27051) (xy 0.22606 -0.25908)
						(xy 0.22352 -0.24892) (xy 0.22225 -0.23876) (xy 0.21844 -0.22733) (xy 0.2159 -0.21717) (xy 0.21209 -0.20701)
						(xy 0.20701 -0.19685) (xy 0.2032 -0.18796) (xy 0.19812 -0.1778) (xy 0.17272 -0.14224) (xy 0.1651 -0.13462)
						(xy 0.1651 0.7366) (xy 0.16256 0.76835) (xy 0.1524 0.8001) (xy 0.13716 0.82804) (xy 0.11684 0.85344)
						(xy 0.09144 0.87376) (xy 0.0635 0.889) (xy 0.03175 0.89916)
					)
					(width 0)
					(fill yes)
				)
			)
		)
		(pad "62" smd custom
			(at -13.349986 -4.106672)
			(size 0.1143 0.1143)
			(layers "F.Cu" "F.Mask" "F.Paste")
			(net "M_B_DQS_DP3")
			(options
				(clearance outline)
				(anchor circle)
			)
			(primitives
				(gr_poly
					(pts
						(xy 0 0.9017) (xy -0.03175 0.89916) (xy -0.0635 0.889) (xy -0.09144 0.87376) (xy -0.11684 0.85344)
						(xy -0.13716 0.82804) (xy -0.1524 0.8001) (xy -0.16256 0.76835) (xy -0.1651 0.7366) (xy -0.1651 0.44958)
						(xy -0.17272 0.44196) (xy -0.19812 0.4064) (xy -0.2032 0.39624) (xy -0.20701 0.38735) (xy -0.21209 0.37719)
						(xy -0.2159 0.36703) (xy -0.21844 0.35687) (xy -0.22225 0.34544) (xy -0.22352 0.33528) (xy -0.22606 0.32512)
						(xy -0.22733 0.31369) (xy -0.22733 0.30353) (xy -0.2286 0.2921) (xy -0.22733 0.28067) (xy -0.22733 0.27051)
						(xy -0.22606 0.25908) (xy -0.22352 0.24892) (xy -0.22225 0.23876) (xy -0.21844 0.22733) (xy -0.2159 0.21717)
						(xy -0.21209 0.20701) (xy -0.20701 0.19685) (xy -0.2032 0.18796) (xy -0.19812 0.1778) (xy -0.17272 0.14224)
						(xy -0.1651 0.13462) (xy -0.1651 -0.7366) (xy -0.16256 -0.76835) (xy -0.1524 -0.8001) (xy -0.13716 -0.82804)
						(xy -0.11684 -0.85344) (xy -0.09144 -0.87376) (xy -0.0635 -0.889) (xy -0.03175 -0.89916) (xy 0 -0.9017)
						(xy 0.03175 -0.89916) (xy 0.0635 -0.889) (xy 0.09144 -0.87376) (xy 0.11684 -0.85344) (xy 0.13716 -0.82804)
						(xy 0.1524 -0.8001) (xy 0.16256 -0.76835) (xy 0.1651 -0.7366) (xy 0.1651 0.13462) (xy 0.17272 0.14224)
						(xy 0.19812 0.1778) (xy 0.2032 0.18796) (xy 0.20701 0.19685) (xy 0.21209 0.20701) (xy 0.2159 0.21717)
						(xy 0.21844 0.22733) (xy 0.22225 0.23876) (xy 0.22352 0.24892) (xy 0.22606 0.25908) (xy 0.22733 0.27051)
						(xy 0.22733 0.28067) (xy 0.2286 0.2921) (xy 0.22733 0.30353) (xy 0.22733 0.31369) (xy 0.22606 0.32512)
						(xy 0.22352 0.33528) (xy 0.22225 0.34544) (xy 0.21844 0.35687) (xy 0.2159 0.36703) (xy 0.21209 0.37719)
						(xy 0.20701 0.38735) (xy 0.2032 0.39624) (xy 0.19812 0.4064) (xy 0.17272 0.44196) (xy 0.1651 0.44958)
						(xy 0.1651 0.7366) (xy 0.16256 0.76835) (xy 0.1524 0.8001) (xy 0.13716 0.82804) (xy 0.11684 0.85344)
						(xy 0.09144 0.87376) (xy 0.0635 0.889) (xy 0.03175 0.89916)
					)
					(width 0)
					(fill yes)
				)
			)
		)
	)
)
